FILE_TYPE = CONNECTIVITY;
{Allegro Design Entry HDL 16.6-p007 (v16-6-112F) 10/10/2012}
"PAGE_NUMBER" = 148;
0"NC";
1"VCC_D_3V3\g";
2"P1V2_AUX_BMC\g";
3"VCC_VA_3V3\g";
4"P3V3_STBY\g";
5"P1V15_AUX_BMC\g";
6"P3V3_STBY\g";
7"PVCCIO_CPU0\g";
8"GND\g";
9"VCC_ADCAV3V3\g";
10"VCC_A_1V1\g";
11"GND\g";
12"P3V3_STBY\g";
13"VCC_DACAV3V3\g";
14"P3V3_USB2A_ALG\g";
15"VCC_PA_3V3\g";
16"VCC_D_3V3\g";
17"PVCCIO_CPU0_R";
18"FM_SLPS3_N";
19"FM_SLPS4_N";
20"VCCBAT_TW12";
21"BMC_JTAG_SEL_N";
%"W_VCC_CIRCLE"
"1","(-5875,3650)","0","w_power","I10";
;
HDL_POWER"VCC_D_3V3"
CDS_LIB"w_power"
CDS_LMAN_SYM_OUTLINE"-100,100,100,-100"
BODY_TYPE"PLUMBING";
"VCC_CIRCLE \B"1;
%"W_VCC_CIRCLE"
"1","(-5675,2900)","0","w_power","I14";
;
HDL_POWER"P1V2_AUX_BMC"
CDS_LMAN_SYM_OUTLINE"-100,100,100,-100"
CDS_LIB"w_power"
BODY_TYPE"PLUMBING";
"VCC_CIRCLE \B"2;
%"W_VCC_CIRCLE"
"1","(-6300,3950)","0","w_power","I15";
;
HDL_POWER"VCC_VA_3V3"
CDS_LMAN_SYM_OUTLINE"-100,100,100,-100"
CDS_LIB"w_power"
BODY_TYPE"PLUMBING";
"VCC_CIRCLE \B"3;
%"RES"
"1","(-6550,3850)","0","mstr_discrete","I16";
;
CDS_SEC"1"
CDS_LOCATION"R25W59"
PACK_TYPE"0402"
TOLERANCE"5%"
VALUE"0.0"
LOCATION"R25W59"
MATERIAL"CHIP"
PART_NUMBER"G21497-005"
WATTAGE"1/16W"
ROOM"USB"
BOM_COST"MIO_USB"
CDS_LIB"mstr_discrete"
SEC"1"
SEC_TYPE"0402";
"B"
$PN"2"20;
"A"
$PN"1"4;
%"P3V3_STBY"
"1","(-6900,4075)","0","mstr_symbols","I18";
;
VOLTAGE"3.3V"
CDS_LIB"mstr_symbols"
SIZE"1B"
BODY_TYPE"PLUMBING"
HDL_POWER"P3V3_STBY";
"G\NAC"4;
%"W_VCC_CIRCLE"
"1","(-6225,2175)","0","w_power","I19";
;
HDL_POWER"P1V15_AUX_BMC"
CDS_LIB"w_power"
CDS_LMAN_SYM_OUTLINE"-100,100,100,-100"
BODY_TYPE"PLUMBING";
"VCC_CIRCLE \B"5;
%"P3V3_STBY"
"1","(-2350,4500)","0","mstr_symbols","I2";
;
SIZE"1B"
VOLTAGE"3.3V"
CDS_LIB"mstr_symbols"
BODY_TYPE"PLUMBING"
HDL_POWER"P3V3_STBY";
"G\NAC"6;
%"CAP_A"
"1","(-7350,2125)","0","dev_discrete","I20";
;
PACK_TYPE"0402V"
MATERIAL"X6S"
VOLTAGE"6.3V"
TOLERANCE"10%"
VALUE"1.0UF"
LOCATION"C1T21"
PART_NUMBER"D97712-004"
CDS_LOCATION"C1T21"
BOM_COST"SM_CONTROLLER"
CDS_LIB"dev_discrete"
CDS_SEC"1"
SEC_TYPE"0402V"
SEC"1"
ROOM"BMC";
"B"
$PN"2"8;
"A"
$PN"1"7;
%"PVCCIO_CPU0"
"1","(-7350,2400)","0","mstr_symbols","I21";
;
CDS_LIB"mstr_symbols"
VOLTAGE"1.1V"
BODY_TYPE"PLUMBING"
HDL_POWER"PVCCIO_CPU0";
"G\NAC"7;
%"GND"
"1","(-7350,1875)","0","mstr_symbols","I22";
;
VOLTAGE"0.0V"
SIZE"1B"
CDS_LIB"mstr_symbols"
BODY_TYPE"PLUMBING"
HDL_POWER"GND";
"A\NAC"8;
%"W_VCC_CIRCLE"
"1","(-5350,4400)","0","w_power","I26";
;
HDL_POWER"VCC_ADCAV3V3"
CDS_LIB"w_power"
CDS_LMAN_SYM_OUTLINE"-100,100,100,-100"
BODY_TYPE"PLUMBING";
"VCC_CIRCLE \B"9;
%"W_VCC_CIRCLE"
"1","(-5300,2050)","0","w_power","I27";
;
HDL_POWER"VCC_A_1V1"
CDS_LMAN_SYM_OUTLINE"-100,100,100,-100"
CDS_LIB"w_power"
BODY_TYPE"PLUMBING";
"VCC_CIRCLE \B"10;
%"AST2520A1-GP-GP"
"7","(-3600,2600)","0","w_hdl","I28";
;
CDS_SEC"7"
$SEC"7"
CDS_LOCATION"U25W4"
VALUE"AST2520A1-GP-GP"
$LOCATION"U25W4"
CDS_LIB"w_hdl"
PART_NUMBER"071.2520A.M001"
PACK_TYPE"ASIC2-GB1"
CDS_LMAN_SYM_OUTLINE"-850,2100,850,-2100";
"GND0"
$PN"A1"11;
"GND1"
$PN"A22"11;
"GND2"
$PN"AA11"11;
"GND3"
$PN"AA13"11;
"GND6"
$PN"AA9"11;
"GND8"
$PN"AB22"11;
"GND7"
$PN"AB1"11;
"GND5"
$PN"AA7"11;
"GND4"
$PN"AA15"11;
"GND11"
$PN"F16"11;
"GND12"
$PN"G19"11;
"GND13"
$PN"G6"11;
"GND10"
$PN"E8"11;
"GND9"
$PN"C6"11;
"GND16"
$PN"J11"11;
"GND17"
$PN"J12"11;
"GND18"
$PN"J13"11;
"GND15"
$PN"J10"11;
"GND14"
$PN"H6"11;
"GND19"
$PN"J14"11;
"GND21"
$PN"J22"11;
"GND22"
$PN"J5"11;
"GND23"
$PN"J9"11;
"GND20"
$PN"J21"11;
"GND24"
$PN"K10"11;
"GND26"
$PN"K12"11;
"GND28"
$PN"K14"11;
"GND27"
$PN"K13"11;
"GND25"
$PN"K11"11;
"GND29"
$PN"K16"11;
"GND31"
$PN"L10"11;
"GND32"
$PN"L11"11;
"GND33"
$PN"L12"11;
"GND34"
$PN"L13"11;
"GND30"
$PN"K9"11;
"GND36"
$PN"L9"11;
"GND37"
$PN"M1"11;
"GND38"
$PN"M10"11;
"GND39"
$PN"M11"11;
"GND35"
$PN"L14"11;
"GND42"
$PN"M14"11;
"GND43"
$PN"M16"11;
"GND44"
$PN"M17"11;
"GND41"
$PN"M13"11;
"GND40"
$PN"M12"11;
"GND47"
$PN"M4"11;
"GND48"
$PN"M5"11;
"GND49"
$PN"M6"11;
"GND46"
$PN"M3"11;
"GND45"
$PN"M2"11;
"GND52"
$PN"N10"11;
"GND53"
$PN"N11"11;
"GND54"
$PN"N12"11;
"GND51"
$PN"M9"11;
"GND50"
$PN"M7"11;
"GND57"
$PN"N9"11;
"GND58"
$PN"T16"11;
"GND59"
$PN"T6"11;
"GND56"
$PN"N14"11;
"GND55"
$PN"N13"11;
"GND62"
$PN"U6"11;
"GND63"
$PN"V10"11;
"GND64"
$PN"V12"11;
"GND61"
$PN"U11"11;
"GND60"
$PN"T7"11;
"GND65"
$PN"V14"11;
"GND66"
$PN"V16"11;
"GND67"
$PN"V8"11;
"R1VDD1"
$PN"F11"12;
"R1VDD0"
$PN"F10"12;
"R2VDD1"
$PN"F8"12;
"R2VDD0"
$PN"F7"12;
"ADCAV33"
$PN"J6"9;
"DACDV33"
$PN"K5"13;
"USB2AV33"
$PN"C7"14;
"BATVDD"
$PN"E4"20;
"PEAV33"
$PN"L16"16;
"VPLLAV331"
$PN"H7"3;
"VPLLAV330"
$PN"J7"3;
"PLLAV331"
$PN"W17"15;
"PLLAV330"
$PN"Y17"15;
"PV33D14"
$PN"T15"1;
"PV33D13"
$PN"T11"15;
"PV33D12"
$PN"R6"1;
"PV33D11"
$PN"R17"1;
"PV33D10"
$PN"P6"1;
"PV33D9"
$PN"P17"1;
"PV33D8"
$PN"N6"1;
"PV33D7"
$PN"N17"1;
"PV33D6"
$PN"K7"1;
"PV33D5"
$PN"H17"1;
"PV33D4"
$PN"G16"1;
"PV33D3"
$PN"F15"1;
"PV33D2"
$PN"F14"1;
"PV33D1"
$PN"F13"1;
"MVDD3"
$PN"T14"2;
"MVDD2"
$PN"T13"2;
"MVDD1"
$PN"T12"2;
"MVDD0"
$PN"T10"2;
"PECIVDD"
$PN"AA17"17;
"PLLDV11"
$PN"V17"5;
"PEAV11"
$PN"L17"5;
"VPLLAV111"
$PN"L6"10;
"VPLLAV110"
$PN"L5"10;
"IV11D24"
$PN"R7"5;
"IV11D23"
$PN"R16"5;
"IV11D22"
$PN"P9"5;
"IV11D21"
$PN"P7"5;
"IV11D20"
$PN"P16"5;
"IV11D19"
$PN"P14"5;
"IV11D18"
$PN"P13"5;
"IV11D17"
$PN"P12"5;
"IV11D16"
$PN"P11"5;
"IV11D15"
$PN"P10"5;
"IV11D14"
$PN"N7"5;
"IV11D13"
$PN"N16"5;
"IV11D12"
$PN"L7"5;
"IV11D11"
$PN"J16"5;
"IV11D10"
$PN"H16"5;
"IV11D9"
$PN"G9"5;
"IV11D8"
$PN"G8"5;
"IV11D7"
$PN"G7"5;
"IV11D6"
$PN"G15"5;
"IV11D5"
$PN"G14"5;
"IV11D4"
$PN"G13"5;
"IV11D3"
$PN"G12"5;
"IV11D2"
$PN"G11"5;
"IV11D1"
$PN"G10"5;
"IV11D0"
$PN"F6"5;
"GPIOY0_SIOS3# \B"
$PN"R22"18;
"GPIOY1_SIOS5# \B"
$PN"R21"19;
"GPIOY2_SIOPWREQ# \B"
$PN"P22"21;
"MVDD4"
$PN"T8"2;
"PV33D0"
$PN"F12"1;
"DACAV33"
$PN"K6"13;
"GND68"
$PN"E5"11;
"LPVDD0"
$PN"J17"6;
"LPVDD1"
$PN"K17"6;
%"RES"
"1","(-6850,2300)","0","mstr_discrete","I29";
;
CDS_SEC"1"
CDS_LOCATION"R25W155"
TOLERANCE"5%"
MATERIAL"CHIP"
PACK_TYPE"0402"
VALUE"0.0"
WATTAGE"1/16W"
PART_NUMBER"G21497-005"
LOCATION"R25W155"
ROOM"USB"
BOM_COST"MIO_USB"
CDS_LIB"mstr_discrete"
SEC"1"
SEC_TYPE"0402";
"B"
$PN"2"17;
"A"
$PN"1"7;
%"GND"
"1","(-2350,500)","0","mstr_symbols","I3";
;
CDS_LIB"mstr_symbols"
SIZE"1B"
VOLTAGE"0.0V"
BODY_TYPE"PLUMBING"
HDL_POWER"GND";
"A\NAC"11;
%"P3V3_STBY"
"1","(-4950,4650)","0","mstr_symbols","I4";
;
VOLTAGE"3.3V"
SIZE"1B"
CDS_LIB"mstr_symbols"
BODY_TYPE"PLUMBING"
HDL_POWER"P3V3_STBY";
"G\NAC"12;
%"W_VCC_CIRCLE"
"1","(-6000,4300)","0","w_power","I6";
;
HDL_POWER"VCC_DACAV3V3"
CDS_LIB"w_power"
CDS_LMAN_SYM_OUTLINE"-100,100,100,-100"
BODY_TYPE"PLUMBING";
"VCC_CIRCLE \B"13;
%"W_VCC_CIRCLE"
"1","(-6400,4200)","0","w_power","I7";
;
HDL_POWER"P3V3_USB2A_ALG"
CDS_LMAN_SYM_OUTLINE"-100,100,100,-100"
CDS_LIB"w_power"
BODY_TYPE"PLUMBING";
"VCC_CIRCLE \B"14;
%"W_VCC_CIRCLE"
"1","(-5025,3725)","0","w_power","I8";
;
HDL_POWER"VCC_PA_3V3"
CDS_LMAN_SYM_OUTLINE"-100,100,100,-100"
CDS_LIB"w_power"
BODY_TYPE"PLUMBING";
"VCC_CIRCLE \B"15;
%"W_VCC_CIRCLE"
"1","(-5350,4000)","0","w_power","I9";
;
HDL_POWER"VCC_D_3V3"
CDS_LIB"w_power"
CDS_LMAN_SYM_OUTLINE"-100,100,100,-100"
BODY_TYPE"PLUMBING";
"VCC_CIRCLE \B"16;
END.
